(kicad_pcb
	(version 20260206)
	(generator "pcbnew")
	(generator_version "10.0")
	(general
		(thickness 1.6)
		(legacy_teardrops no)
	)
	(paper "A4")
	(title_block
		(title "01162023_DA0F0TEBIF0_F0T_Expander_BD_F_brd_V02_OCP.brd")
		(comment 1 "Grand Teton / footprints 3456-3462 of 9728")
	)
	(layers
		(0 "F.Cu" signal "TOP")
		(4 "In1.Cu" signal "GND")
		(6 "In2.Cu" signal "VCC")
		(8 "In3.Cu" signal "VCC1")
		(10 "In4.Cu" signal "GND1")
		(12 "In5.Cu" signal "IN1")
		(14 "In6.Cu" signal "GND2")
		(16 "In7.Cu" signal "IN2")
		(18 "In8.Cu" signal "GND3")
		(20 "In9.Cu" signal "IN3")
		(22 "In10.Cu" signal "GND4")
		(24 "In11.Cu" signal "IN4")
		(26 "In12.Cu" signal "GND5")
		(28 "In13.Cu" signal "IN5")
		(30 "In14.Cu" signal "GND6")
		(32 "In15.Cu" signal "IN6")
		(34 "In16.Cu" signal "GND7")
		(2 "B.Cu" signal "BOTTOM")
		(9 "F.Adhes" user "F.Adhesive")
		(11 "B.Adhes" user "B.Adhesive")
		(13 "F.Paste" user "Package Geometry/Pastemask Top")
		(15 "B.Paste" user "Package Geometry/Pastemask Bottom")
		(5 "F.SilkS" user "Ref Des/Silkscreen Top")
		(7 "B.SilkS" user "Ref Des/Silkscreen Bottom")
		(1 "F.Mask" user "Board Geometry/Soldermask Top")
		(3 "B.Mask" user "Board Geometry/Soldermask Bottom")
		(17 "Dwgs.User" user "User.Drawings")
		(19 "Cmts.User" user "User.Comments")
		(21 "Eco1.User" user "User.Eco1")
		(23 "Eco2.User" user "User.Eco2")
		(25 "Edge.Cuts" user "Board Geometry/Outline")
		(27 "Margin" user)
		(31 "F.CrtYd" user "Package Geometry/Place Bound Top")
		(29 "B.CrtYd" user "Package Geometry/Place Bound Bottom")
		(35 "F.Fab" user "Ref Des/Assembly Top")
		(33 "B.Fab" user "Ref Des/Assembly Bottom")
	)
	(footprint ""
		(layer "F.Cu")
		(at 378.453396 -294.591232)
		(property "Reference" "L138"
			(at 0 0 0)
			(layer "F.SilkS")
			(hide yes)
			(effects
				(font
					(size 1.27 1.27)
				)
			)
		)
		(property "Value" ""
			(at 0 0 0)
			(layer "F.Fab")
			(effects
				(font
					(size 1.27 1.27)
				)
			)
		)
		(duplicate_pad_numbers_are_jumpers no)
		(fp_line
			(start -1.63576 -0.8128)
			(end -1.63576 0.8128)
			(stroke
				(width 0.1524)
				(type default)
			)
			(layer "F.SilkS")
		)
		(fp_line
			(start -1.63576 -0.8128)
			(end 1.63576 -0.8128)
			(stroke
				(width 0.1524)
				(type default)
			)
			(layer "F.SilkS")
		)
		(fp_line
			(start 1.63576 -0.8128)
			(end 1.63576 0.8128)
			(stroke
				(width 0.1524)
				(type default)
			)
			(layer "F.SilkS")
		)
		(fp_line
			(start 1.63576 0.8128)
			(end -1.63576 0.8128)
			(stroke
				(width 0.1524)
				(type default)
			)
			(layer "F.SilkS")
		)
		(fp_line
			(start -1.56083 -0.738632)
			(end -1.56083 0.7366)
			(stroke
				(width 0.1)
				(type default)
			)
			(layer "F.Fab")
		)
		(fp_line
			(start -1.56083 0.7366)
			(end -1.524 0.7366)
			(stroke
				(width 0.1)
				(type default)
			)
			(layer "F.Fab")
		)
		(fp_line
			(start -1.524 0.7366)
			(end 1.524 0.7366)
			(stroke
				(width 0.1)
				(type default)
			)
			(layer "F.Fab")
		)
		(fp_line
			(start 1.524 0.7366)
			(end 1.560576 0.7366)
			(stroke
				(width 0.1)
				(type default)
			)
			(layer "F.Fab")
		)
		(fp_line
			(start 1.560576 -0.738632)
			(end -1.56083 -0.738632)
			(stroke
				(width 0.1)
				(type default)
			)
			(layer "F.Fab")
		)
		(fp_line
			(start 1.560576 0.7366)
			(end 1.560576 -0.738632)
			(stroke
				(width 0.1)
				(type default)
			)
			(layer "F.Fab")
		)
		(pad "1" smd rect
			(at -0.94996 0 180)
			(size 1.1176 1.3716)
			(layers "F.Cu" "F.Mask" "F.Paste")
			(net "P1V8_PLL0_PEX3")
		)
		(pad "2" smd rect
			(at 0.94996 0 180)
			(size 1.1176 1.3716)
			(layers "F.Cu" "F.Mask" "F.Paste")
			(net "PCEPLL2_VDDA18_PEX3")
		)
	)
	(footprint ""
		(layer "F.Cu")
		(at 22.416008 -356.244906 90)
		(property "Reference" "C187"
			(at 0 0 90)
			(layer "F.SilkS")
			(hide yes)
			(effects
				(font
					(size 1.27 1.27)
				)
			)
		)
		(property "Value" ""
			(at 0 0 90)
			(layer "F.Fab")
			(effects
				(font
					(size 1.27 1.27)
				)
			)
		)
		(duplicate_pad_numbers_are_jumpers no)
		(fp_line
			(start 0.299974 -0.150114)
			(end 0.299974 0.150114)
			(stroke
				(width 0.1)
				(type default)
			)
			(layer "F.Fab")
		)
		(fp_line
			(start -0.299974 -0.150114)
			(end 0.299974 -0.150114)
			(stroke
				(width 0.1)
				(type default)
			)
			(layer "F.Fab")
		)
		(fp_line
			(start 0.299974 0.150114)
			(end -0.299974 0.150114)
			(stroke
				(width 0.1)
				(type default)
			)
			(layer "F.Fab")
		)
		(fp_line
			(start -0.299974 0.150114)
			(end -0.299974 -0.150114)
			(stroke
				(width 0.1)
				(type default)
			)
			(layer "F.Fab")
		)
		(pad "1" smd rect
			(at -0.2667 0 90)
			(size 0.3048 0.381)
			(layers "F.Cu" "F.Mask" "F.Paste")
			(net "P5E_PEX0_STN7_TX_DP<114>")
		)
		(pad "2" smd rect
			(at 0.2667 0 90)
			(size 0.3048 0.381)
			(layers "F.Cu" "F.Mask" "F.Paste")
			(net "P5E_PEX0_STN7_TX_C_DP<114>")
		)
	)
	(footprint ""
		(layer "F.Cu")
		(at 56.373268 -390.11479 -90)
		(property "Reference" "C4040"
			(at 0 0 270)
			(layer "F.SilkS")
			(hide yes)
			(effects
				(font
					(size 1.27 1.27)
				)
			)
		)
		(property "Value" ""
			(at 0 0 270)
			(layer "F.Fab")
			(effects
				(font
					(size 1.27 1.27)
				)
			)
		)
		(duplicate_pad_numbers_are_jumpers no)
		(fp_line
			(start -0.7874 0.4064)
			(end -0.7874 -0.4064)
			(stroke
				(width 0.1524)
				(type default)
			)
			(layer "F.SilkS")
		)
		(fp_line
			(start 0.7874 0.4064)
			(end -0.7874 0.4064)
			(stroke
				(width 0.1524)
				(type default)
			)
			(layer "F.SilkS")
		)
		(fp_line
			(start -0.7874 -0.4064)
			(end 0.7874 -0.4064)
			(stroke
				(width 0.1524)
				(type default)
			)
			(layer "F.SilkS")
		)
		(fp_line
			(start 0.7874 -0.4064)
			(end 0.7874 0.4064)
			(stroke
				(width 0.1524)
				(type default)
			)
			(layer "F.SilkS")
		)
		(fp_line
			(start -0.67945 0.3048)
			(end -0.67945 -0.305054)
			(stroke
				(width 0.1)
				(type default)
			)
			(layer "F.Fab")
		)
		(fp_line
			(start -0.12065 0.3048)
			(end -0.67945 0.3048)
			(stroke
				(width 0.1)
				(type default)
			)
			(layer "F.Fab")
		)
		(fp_line
			(start 0.120396 0.3048)
			(end 0.120396 0.2794)
			(stroke
				(width 0.1)
				(type default)
			)
			(layer "F.Fab")
		)
		(fp_line
			(start 0.67945 0.3048)
			(end 0.120396 0.3048)
			(stroke
				(width 0.1)
				(type default)
			)
			(layer "F.Fab")
		)
		(fp_line
			(start -0.12065 0.2794)
			(end -0.12065 0.3048)
			(stroke
				(width 0.1)
				(type default)
			)
			(layer "F.Fab")
		)
		(fp_line
			(start 0.120396 0.2794)
			(end -0.12065 0.2794)
			(stroke
				(width 0.1)
				(type default)
			)
			(layer "F.Fab")
		)
		(fp_line
			(start -0.12065 -0.2794)
			(end 0.12065 -0.2794)
			(stroke
				(width 0.1)
				(type default)
			)
			(layer "F.Fab")
		)
		(fp_line
			(start 0.12065 -0.2794)
			(end 0.12065 -0.3048)
			(stroke
				(width 0.1)
				(type default)
			)
			(layer "F.Fab")
		)
		(fp_line
			(start 0.12065 -0.3048)
			(end 0.67945 -0.3048)
			(stroke
				(width 0.1)
				(type default)
			)
			(layer "F.Fab")
		)
		(fp_line
			(start 0.67945 -0.3048)
			(end 0.67945 0.3048)
			(stroke
				(width 0.1)
				(type default)
			)
			(layer "F.Fab")
		)
		(fp_line
			(start -0.67945 -0.305054)
			(end -0.12065 -0.305054)
			(stroke
				(width 0.1)
				(type default)
			)
			(layer "F.Fab")
		)
		(fp_line
			(start -0.12065 -0.305054)
			(end -0.12065 -0.2794)
			(stroke
				(width 0.1)
				(type default)
			)
			(layer "F.Fab")
		)
		(pad "1" smd circle
			(at -0.40005 0 270)
			(size 0 0)
			(layers "F.Cu" "F.Mask" "F.Paste")
			(net "GND")
		)
		(pad "2" smd circle
			(at 0.40005 0 270)
			(size 0 0)
			(layers "F.Cu" "F.Mask" "F.Paste")
			(net "GPU_PEX_STRAP0")
		)
	)
	(footprint ""
		(layer "F.Cu")
		(at 258.170426 -242.372388)
		(property "Reference" "C4428"
			(at 0 0 0)
			(layer "F.SilkS")
			(hide yes)
			(effects
				(font
					(size 1.27 1.27)
				)
			)
		)
		(property "Value" ""
			(at 0 0 0)
			(layer "F.Fab")
			(effects
				(font
					(size 1.27 1.27)
				)
			)
		)
		(duplicate_pad_numbers_are_jumpers no)
		(fp_line
			(start -0.7874 -0.4064)
			(end 0.7874 -0.4064)
			(stroke
				(width 0.1524)
				(type default)
			)
			(layer "F.SilkS")
		)
		(fp_line
			(start -0.7874 0.4064)
			(end -0.7874 -0.4064)
			(stroke
				(width 0.1524)
				(type default)
			)
			(layer "F.SilkS")
		)
		(fp_line
			(start 0.7874 -0.4064)
			(end 0.7874 0.4064)
			(stroke
				(width 0.1524)
				(type default)
			)
			(layer "F.SilkS")
		)
		(fp_line
			(start 0.7874 0.4064)
			(end -0.7874 0.4064)
			(stroke
				(width 0.1524)
				(type default)
			)
			(layer "F.SilkS")
		)
		(fp_line
			(start -0.67945 -0.305054)
			(end -0.12065 -0.305054)
			(stroke
				(width 0.1)
				(type default)
			)
			(layer "F.Fab")
		)
		(fp_line
			(start -0.67945 0.3048)
			(end -0.67945 -0.305054)
			(stroke
				(width 0.1)
				(type default)
			)
			(layer "F.Fab")
		)
		(fp_line
			(start -0.12065 -0.305054)
			(end -0.12065 -0.2794)
			(stroke
				(width 0.1)
				(type default)
			)
			(layer "F.Fab")
		)
		(fp_line
			(start -0.12065 -0.2794)
			(end 0.12065 -0.2794)
			(stroke
				(width 0.1)
				(type default)
			)
			(layer "F.Fab")
		)
		(fp_line
			(start -0.12065 0.2794)
			(end -0.12065 0.3048)
			(stroke
				(width 0.1)
				(type default)
			)
			(layer "F.Fab")
		)
		(fp_line
			(start -0.12065 0.3048)
			(end -0.67945 0.3048)
			(stroke
				(width 0.1)
				(type default)
			)
			(layer "F.Fab")
		)
		(fp_line
			(start 0.120396 0.2794)
			(end -0.12065 0.2794)
			(stroke
				(width 0.1)
				(type default)
			)
			(layer "F.Fab")
		)
		(fp_line
			(start 0.120396 0.3048)
			(end 0.120396 0.2794)
			(stroke
				(width 0.1)
				(type default)
			)
			(layer "F.Fab")
		)
		(fp_line
			(start 0.12065 -0.3048)
			(end 0.67945 -0.3048)
			(stroke
				(width 0.1)
				(type default)
			)
			(layer "F.Fab")
		)
		(fp_line
			(start 0.12065 -0.2794)
			(end 0.12065 -0.3048)
			(stroke
				(width 0.1)
				(type default)
			)
			(layer "F.Fab")
		)
		(fp_line
			(start 0.67945 -0.3048)
			(end 0.67945 0.3048)
			(stroke
				(width 0.1)
				(type default)
			)
			(layer "F.Fab")
		)
		(fp_line
			(start 0.67945 0.3048)
			(end 0.120396 0.3048)
			(stroke
				(width 0.1)
				(type default)
			)
			(layer "F.Fab")
		)
		(pad "1" smd circle
			(at -0.40005 0)
			(size 0 0)
			(layers "F.Cu" "F.Mask" "F.Paste")
			(net "PEX2_P1V8_PLL_EN")
		)
		(pad "2" smd circle
			(at 0.40005 0)
			(size 0 0)
			(layers "F.Cu" "F.Mask" "F.Paste")
			(net "GND")
		)
	)
	(footprint ""
		(layer "F.Cu")
		(at 265.303254 -59.571636 90)
		(property "Reference" "PR277"
			(at 0 0 90)
			(layer "F.SilkS")
			(hide yes)
			(effects
				(font
					(size 1.27 1.27)
				)
			)
		)
		(property "Value" ""
			(at 0 0 90)
			(layer "F.Fab")
			(effects
				(font
					(size 1.27 1.27)
				)
			)
		)
		(duplicate_pad_numbers_are_jumpers no)
		(fp_line
			(start 0.7874 -0.4064)
			(end 0.7874 0.4064)
			(stroke
				(width 0.1524)
				(type default)
			)
			(layer "F.SilkS")
		)
		(fp_line
			(start -0.7874 -0.4064)
			(end 0.7874 -0.4064)
			(stroke
				(width 0.1524)
				(type default)
			)
			(layer "F.SilkS")
		)
		(fp_line
			(start 0.7874 0.4064)
			(end -0.7874 0.4064)
			(stroke
				(width 0.1524)
				(type default)
			)
			(layer "F.SilkS")
		)
		(fp_line
			(start -0.7874 0.4064)
			(end -0.7874 -0.4064)
			(stroke
				(width 0.1524)
				(type default)
			)
			(layer "F.SilkS")
		)
		(fp_line
			(start -0.12065 -0.305054)
			(end -0.12065 -0.2794)
			(stroke
				(width 0.1)
				(type default)
			)
			(layer "F.Fab")
		)
		(fp_line
			(start -0.67945 -0.305054)
			(end -0.12065 -0.305054)
			(stroke
				(width 0.1)
				(type default)
			)
			(layer "F.Fab")
		)
		(fp_line
			(start 0.67945 -0.3048)
			(end 0.67945 0.3048)
			(stroke
				(width 0.1)
				(type default)
			)
			(layer "F.Fab")
		)
		(fp_line
			(start 0.12065 -0.3048)
			(end 0.67945 -0.3048)
			(stroke
				(width 0.1)
				(type default)
			)
			(layer "F.Fab")
		)
		(fp_line
			(start 0.12065 -0.2794)
			(end 0.12065 -0.3048)
			(stroke
				(width 0.1)
				(type default)
			)
			(layer "F.Fab")
		)
		(fp_line
			(start -0.12065 -0.2794)
			(end 0.12065 -0.2794)
			(stroke
				(width 0.1)
				(type default)
			)
			(layer "F.Fab")
		)
		(fp_line
			(start 0.120396 0.2794)
			(end -0.12065 0.2794)
			(stroke
				(width 0.1)
				(type default)
			)
			(layer "F.Fab")
		)
		(fp_line
			(start -0.12065 0.2794)
			(end -0.12065 0.3048)
			(stroke
				(width 0.1)
				(type default)
			)
			(layer "F.Fab")
		)
		(fp_line
			(start 0.67945 0.3048)
			(end 0.120396 0.3048)
			(stroke
				(width 0.1)
				(type default)
			)
			(layer "F.Fab")
		)
		(fp_line
			(start 0.120396 0.3048)
			(end 0.120396 0.2794)
			(stroke
				(width 0.1)
				(type default)
			)
			(layer "F.Fab")
		)
		(fp_line
			(start -0.12065 0.3048)
			(end -0.67945 0.3048)
			(stroke
				(width 0.1)
				(type default)
			)
			(layer "F.Fab")
		)
		(fp_line
			(start -0.67945 0.3048)
			(end -0.67945 -0.305054)
			(stroke
				(width 0.1)
				(type default)
			)
			(layer "F.Fab")
		)
		(pad "1" smd circle
			(at -0.40005 0 90)
			(size 0 0)
			(layers "F.Cu" "F.Mask" "F.Paste")
			(net "P3V3_SSD9_OCP")
		)
		(pad "2" smd circle
			(at 0.40005 0 90)
			(size 0 0)
			(layers "F.Cu" "F.Mask" "F.Paste")
			(net "GND")
		)
	)
	(footprint ""
		(layer "F.Cu")
		(at 439.57621 -297.46448 180)
		(property "Reference" "R4007"
			(at 0 0 180)
			(layer "F.SilkS")
			(hide yes)
			(effects
				(font
					(size 1.27 1.27)
				)
			)
		)
		(property "Value" ""
			(at 0 0 180)
			(layer "F.Fab")
			(effects
				(font
					(size 1.27 1.27)
				)
			)
		)
		(duplicate_pad_numbers_are_jumpers no)
		(fp_line
			(start 0.7874 0.4064)
			(end -0.7874 0.4064)
			(stroke
				(width 0.1524)
				(type default)
			)
			(layer "F.SilkS")
		)
		(fp_line
			(start 0.7874 -0.4064)
			(end 0.7874 0.4064)
			(stroke
				(width 0.1524)
				(type default)
			)
			(layer "F.SilkS")
		)
		(fp_line
			(start -0.7874 0.4064)
			(end -0.7874 -0.4064)
			(stroke
				(width 0.1524)
				(type default)
			)
			(layer "F.SilkS")
		)
		(fp_line
			(start -0.7874 -0.4064)
			(end 0.7874 -0.4064)
			(stroke
				(width 0.1524)
				(type default)
			)
			(layer "F.SilkS")
		)
		(fp_line
			(start 0.67945 0.3048)
			(end 0.120396 0.3048)
			(stroke
				(width 0.1)
				(type default)
			)
			(layer "F.Fab")
		)
		(fp_line
			(start 0.67945 -0.3048)
			(end 0.67945 0.3048)
			(stroke
				(width 0.1)
				(type default)
			)
			(layer "F.Fab")
		)
		(fp_line
			(start 0.12065 -0.2794)
			(end 0.12065 -0.3048)
			(stroke
				(width 0.1)
				(type default)
			)
			(layer "F.Fab")
		)
		(fp_line
			(start 0.12065 -0.3048)
			(end 0.67945 -0.3048)
			(stroke
				(width 0.1)
				(type default)
			)
			(layer "F.Fab")
		)
		(fp_line
			(start 0.120396 0.3048)
			(end 0.120396 0.2794)
			(stroke
				(width 0.1)
				(type default)
			)
			(layer "F.Fab")
		)
		(fp_line
			(start 0.120396 0.2794)
			(end -0.12065 0.2794)
			(stroke
				(width 0.1)
				(type default)
			)
			(layer "F.Fab")
		)
		(fp_line
			(start -0.12065 0.3048)
			(end -0.67945 0.3048)
			(stroke
				(width 0.1)
				(type default)
			)
			(layer "F.Fab")
		)
		(fp_line
			(start -0.12065 0.2794)
			(end -0.12065 0.3048)
			(stroke
				(width 0.1)
				(type default)
			)
			(layer "F.Fab")
		)
		(fp_line
			(start -0.12065 -0.2794)
			(end 0.12065 -0.2794)
			(stroke
				(width 0.1)
				(type default)
			)
			(layer "F.Fab")
		)
		(fp_line
			(start -0.12065 -0.305054)
			(end -0.12065 -0.2794)
			(stroke
				(width 0.1)
				(type default)
			)
			(layer "F.Fab")
		)
		(fp_line
			(start -0.67945 0.3048)
			(end -0.67945 -0.305054)
			(stroke
				(width 0.1)
				(type default)
			)
			(layer "F.Fab")
		)
		(fp_line
			(start -0.67945 -0.305054)
			(end -0.12065 -0.305054)
			(stroke
				(width 0.1)
				(type default)
			)
			(layer "F.Fab")
		)
		(pad "1" smd circle
			(at -0.40005 0 180)
			(size 0 0)
			(layers "F.Cu" "F.Mask" "F.Paste")
			(net "SMB_PEX3_HOST_LS_SCL")
		)
		(pad "2" smd circle
			(at 0.40005 0 180)
			(size 0 0)
			(layers "F.Cu" "F.Mask" "F.Paste")
			(net "I2C_PEX3_HOST_R_SCL")
		)
	)
	(footprint ""
		(layer "F.Cu")
		(at 386.899912 -150.263352 180)
		(property "Reference" "R321"
			(at 0 0 180)
			(layer "F.SilkS")
			(hide yes)
			(effects
				(font
					(size 1.27 1.27)
				)
			)
		)
		(property "Value" ""
			(at 0 0 180)
			(layer "F.Fab")
			(effects
				(font
					(size 1.27 1.27)
				)
			)
		)
		(duplicate_pad_numbers_are_jumpers no)
		(fp_line
			(start 0.7874 0.4064)
			(end -0.7874 0.4064)
			(stroke
				(width 0.1524)
				(type default)
			)
			(layer "F.SilkS")
		)
		(fp_line
			(start 0.7874 -0.4064)
			(end 0.7874 0.4064)
			(stroke
				(width 0.1524)
				(type default)
			)
			(layer "F.SilkS")
		)
		(fp_line
			(start -0.7874 0.4064)
			(end -0.7874 -0.4064)
			(stroke
				(width 0.1524)
				(type default)
			)
			(layer "F.SilkS")
		)
		(fp_line
			(start -0.7874 -0.4064)
			(end 0.7874 -0.4064)
			(stroke
				(width 0.1524)
				(type default)
			)
			(layer "F.SilkS")
		)
		(fp_line
			(start 0.67945 0.3048)
			(end 0.120396 0.3048)
			(stroke
				(width 0.1)
				(type default)
			)
			(layer "F.Fab")
		)
		(fp_line
			(start 0.67945 -0.3048)
			(end 0.67945 0.3048)
			(stroke
				(width 0.1)
				(type default)
			)
			(layer "F.Fab")
		)
		(fp_line
			(start 0.12065 -0.2794)
			(end 0.12065 -0.3048)
			(stroke
				(width 0.1)
				(type default)
			)
			(layer "F.Fab")
		)
		(fp_line
			(start 0.12065 -0.3048)
			(end 0.67945 -0.3048)
			(stroke
				(width 0.1)
				(type default)
			)
			(layer "F.Fab")
		)
		(fp_line
			(start 0.120396 0.3048)
			(end 0.120396 0.2794)
			(stroke
				(width 0.1)
				(type default)
			)
			(layer "F.Fab")
		)
		(fp_line
			(start 0.120396 0.2794)
			(end -0.12065 0.2794)
			(stroke
				(width 0.1)
				(type default)
			)
			(layer "F.Fab")
		)
		(fp_line
			(start -0.12065 0.3048)
			(end -0.67945 0.3048)
			(stroke
				(width 0.1)
				(type default)
			)
			(layer "F.Fab")
		)
		(fp_line
			(start -0.12065 0.2794)
			(end -0.12065 0.3048)
			(stroke
				(width 0.1)
				(type default)
			)
			(layer "F.Fab")
		)
		(fp_line
			(start -0.12065 -0.2794)
			(end 0.12065 -0.2794)
			(stroke
				(width 0.1)
				(type default)
			)
			(layer "F.Fab")
		)
		(fp_line
			(start -0.12065 -0.305054)
			(end -0.12065 -0.2794)
			(stroke
				(width 0.1)
				(type default)
			)
			(layer "F.Fab")
		)
		(fp_line
			(start -0.67945 0.3048)
			(end -0.67945 -0.305054)
			(stroke
				(width 0.1)
				(type default)
			)
			(layer "F.Fab")
		)
		(fp_line
			(start -0.67945 -0.305054)
			(end -0.12065 -0.305054)
			(stroke
				(width 0.1)
				(type default)
			)
			(layer "F.Fab")
		)
		(pad "1" smd circle
			(at -0.40005 0 180)
			(size 0 0)
			(layers "F.Cu" "F.Mask" "F.Paste")
			(net "NCSI_NIC6_CRS_DV")
		)
		(pad "2" smd circle
			(at 0.40005 0 180)
			(size 0 0)
			(layers "F.Cu" "F.Mask" "F.Paste")
			(net "GND")
		)
	)
)
